# T6G (Grand Teton) — schematic netlist excerpt (pin names and nets, part order shuffled) for the footprints in the layout excerpt that follows; sources: Cadence DE-HDL packaged netlist, KiCad conversion of 04192023_DAF0TMB3IC0_F0TG_MB_C_brd_V02_OCP.brd

C2203  Q_CAP  22UF 4V 20% X6S  pkg C0402  page 69 : A = PVDDCR_CPU1_P0 ; B = GND
C1016  Q_CAP  1UF 4V 20% X6S  pkg 0201  page 312 : A = P0V9_CPU0_RT_2D ; B = GND
C793  Q_CAP  1UF 4V 20% X6S  pkg 0201  page 301 : A = P0V9_CPU0_RT2_2A_2D ; B = GND
C376  Q_CAP  1UF 4V 20% X6S  pkg 0201  page 345 : A = P1V8_CPU1_RT2_1A ; B = GND

(kicad_pcb
	(version 20260206)
	(generator "pcbnew")
	(generator_version "10.0")
	(general
		(thickness 1.6)
		(legacy_teardrops no)
	)
	(paper "A4")
	(title_block
		(title "04192023_DAF0TMB3IC0_F0TG_MB_C_brd_V02_OCP.brd")
		(comment 1 "Grand Teton / footprints 6062-6065 of 8354")
	)
	(layers
		(0 "F.Cu" signal "TOP")
		(4 "In1.Cu" signal "GND")
		(6 "In2.Cu" signal "IN1")
		(8 "In3.Cu" signal "GND1")
		(10 "In4.Cu" signal "IN2")
		(12 "In5.Cu" signal "GND2")
		(14 "In6.Cu" signal "IN3")
		(16 "In7.Cu" signal "GND3")
		(18 "In8.Cu" signal "VCC")
		(20 "In9.Cu" signal "VCC1")
		(22 "In10.Cu" signal "GND4")
		(24 "In11.Cu" signal "IN4")
		(26 "In12.Cu" signal "GND5")
		(28 "In13.Cu" signal "IN5")
		(30 "In14.Cu" signal "GND6")
		(32 "In15.Cu" signal "IN6")
		(34 "In16.Cu" signal "GND7")
		(2 "B.Cu" signal "BOTTOM")
		(9 "F.Adhes" user "F.Adhesive")
		(11 "B.Adhes" user "B.Adhesive")
		(13 "F.Paste" user "Package Geometry/Pastemask Top")
		(15 "B.Paste" user "Package Geometry/Pastemask Bottom")
		(5 "F.SilkS" user "Ref Des/Silkscreen Top")
		(7 "B.SilkS" user "Ref Des/Silkscreen Bottom")
		(1 "F.Mask" user "Board Geometry/Soldermask Top")
		(3 "B.Mask" user "Board Geometry/Soldermask Bottom")
		(17 "Dwgs.User" user "User.Drawings")
		(19 "Cmts.User" user "User.Comments")
		(21 "Eco1.User" user "User.Eco1")
		(23 "Eco2.User" user "User.Eco2")
		(25 "Edge.Cuts" user "Board Geometry/Outline")
		(27 "Margin" user)
		(31 "F.CrtYd" user "Package Geometry/Place Bound Top")
		(29 "B.CrtYd" user "Package Geometry/Place Bound Bottom")
		(35 "F.Fab" user "Ref Des/Assembly Top")
		(33 "B.Fab" user "Ref Des/Assembly Bottom")
	)
	(footprint ""
		(layer "B.Cu")
		(at 416.206178 -395.148562 90)
		(property "Reference" "C793"
			(at 0 0 90)
			(layer "B.SilkS")
			(hide yes)
			(effects
				(font
					(size 1.27 1.27)
				)
				(justify mirror)
			)
		)
		(property "Value" ""
			(at 0 0 90)
			(layer "B.Fab")
			(effects
				(font
					(size 1.27 1.27)
				)
				(justify mirror)
			)
		)
		(duplicate_pad_numbers_are_jumpers no)
		(fp_line
			(start 0.299974 -0.150114)
			(end -0.299974 -0.150114)
			(stroke
				(width 0.1)
				(type default)
			)
			(layer "B.Fab")
		)
		(fp_line
			(start -0.299974 -0.150114)
			(end -0.299974 0.150114)
			(stroke
				(width 0.1)
				(type default)
			)
			(layer "B.Fab")
		)
		(fp_line
			(start 0.299974 0.150114)
			(end 0.299974 -0.150114)
			(stroke
				(width 0.1)
				(type default)
			)
			(layer "B.Fab")
		)
		(fp_line
			(start -0.299974 0.150114)
			(end 0.299974 0.150114)
			(stroke
				(width 0.1)
				(type default)
			)
			(layer "B.Fab")
		)
		(pad "1" smd rect
			(at 0.2667 0 270)
			(size 0.3048 0.381)
			(layers "B.Cu" "B.Mask" "B.Paste")
			(net "P0V9_CPU0_RT2_2A_2D")
		)
		(pad "2" smd rect
			(at -0.2667 0 270)
			(size 0.3048 0.381)
			(layers "B.Cu" "B.Mask" "B.Paste")
			(net "GND")
		)
	)
	(footprint ""
		(layer "B.Cu")
		(at 155.546298 -388.011162 -90)
		(property "Reference" "C376"
			(at 0 0 90)
			(layer "B.SilkS")
			(hide yes)
			(effects
				(font
					(size 1.27 1.27)
				)
				(justify mirror)
			)
		)
		(property "Value" ""
			(at 0 0 90)
			(layer "B.Fab")
			(effects
				(font
					(size 1.27 1.27)
				)
				(justify mirror)
			)
		)
		(duplicate_pad_numbers_are_jumpers no)
		(fp_line
			(start -0.299974 0.150114)
			(end 0.299974 0.150114)
			(stroke
				(width 0.1)
				(type default)
			)
			(layer "B.Fab")
		)
		(fp_line
			(start 0.299974 0.150114)
			(end 0.299974 -0.150114)
			(stroke
				(width 0.1)
				(type default)
			)
			(layer "B.Fab")
		)
		(fp_line
			(start -0.299974 -0.150114)
			(end -0.299974 0.150114)
			(stroke
				(width 0.1)
				(type default)
			)
			(layer "B.Fab")
		)
		(fp_line
			(start 0.299974 -0.150114)
			(end -0.299974 -0.150114)
			(stroke
				(width 0.1)
				(type default)
			)
			(layer "B.Fab")
		)
		(pad "1" smd rect
			(at 0.2667 0 90)
			(size 0.3048 0.381)
			(layers "B.Cu" "B.Mask" "B.Paste")
			(net "P1V8_CPU1_RT2_1A")
		)
		(pad "2" smd rect
			(at -0.2667 0 90)
			(size 0.3048 0.381)
			(layers "B.Cu" "B.Mask" "B.Paste")
			(net "GND")
		)
	)
	(footprint ""
		(layer "B.Cu")
		(at 357.708454 -268.41831)
		(property "Reference" "C2203"
			(at 0 0 0)
			(layer "B.SilkS")
			(hide yes)
			(effects
				(font
					(size 1.27 1.27)
				)
				(justify mirror)
			)
		)
		(property "Value" ""
			(at 0 0 0)
			(layer "B.Fab")
			(effects
				(font
					(size 1.27 1.27)
				)
				(justify mirror)
			)
		)
		(duplicate_pad_numbers_are_jumpers no)
		(fp_line
			(start -0.7874 -0.4064)
			(end -0.7874 0.4064)
			(stroke
				(width 0.1524)
				(type default)
			)
			(layer "B.SilkS")
		)
		(fp_line
			(start -0.7874 0.4064)
			(end 0.7874 0.4064)
			(stroke
				(width 0.1524)
				(type default)
			)
			(layer "B.SilkS")
		)
		(fp_line
			(start 0.7874 -0.4064)
			(end -0.7874 -0.4064)
			(stroke
				(width 0.1524)
				(type default)
			)
			(layer "B.SilkS")
		)
		(fp_line
			(start 0.7874 0.4064)
			(end 0.7874 -0.4064)
			(stroke
				(width 0.1524)
				(type default)
			)
			(layer "B.SilkS")
		)
		(fp_line
			(start -0.67945 -0.3048)
			(end -0.67945 0.3048)
			(stroke
				(width 0.1)
				(type default)
			)
			(layer "B.Fab")
		)
		(fp_line
			(start -0.67945 0.3048)
			(end -0.120396 0.3048)
			(stroke
				(width 0.1)
				(type default)
			)
			(layer "B.Fab")
		)
		(fp_line
			(start -0.12065 -0.3048)
			(end -0.67945 -0.3048)
			(stroke
				(width 0.1)
				(type default)
			)
			(layer "B.Fab")
		)
		(fp_line
			(start -0.12065 -0.2794)
			(end -0.12065 -0.3048)
			(stroke
				(width 0.1)
				(type default)
			)
			(layer "B.Fab")
		)
		(fp_line
			(start -0.120396 0.2794)
			(end 0.12065 0.2794)
			(stroke
				(width 0.1)
				(type default)
			)
			(layer "B.Fab")
		)
		(fp_line
			(start -0.120396 0.3048)
			(end -0.120396 0.2794)
			(stroke
				(width 0.1)
				(type default)
			)
			(layer "B.Fab")
		)
		(fp_line
			(start 0.12065 -0.305054)
			(end 0.12065 -0.2794)
			(stroke
				(width 0.1)
				(type default)
			)
			(layer "B.Fab")
		)
		(fp_line
			(start 0.12065 -0.2794)
			(end -0.12065 -0.2794)
			(stroke
				(width 0.1)
				(type default)
			)
			(layer "B.Fab")
		)
		(fp_line
			(start 0.12065 0.2794)
			(end 0.12065 0.3048)
			(stroke
				(width 0.1)
				(type default)
			)
			(layer "B.Fab")
		)
		(fp_line
			(start 0.12065 0.3048)
			(end 0.67945 0.3048)
			(stroke
				(width 0.1)
				(type default)
			)
			(layer "B.Fab")
		)
		(fp_line
			(start 0.67945 -0.305054)
			(end 0.12065 -0.305054)
			(stroke
				(width 0.1)
				(type default)
			)
			(layer "B.Fab")
		)
		(fp_line
			(start 0.67945 0.3048)
			(end 0.67945 -0.305054)
			(stroke
				(width 0.1)
				(type default)
			)
			(layer "B.Fab")
		)
		(pad "1" smd circle
			(at 0.40005 0 180)
			(size 0 0)
			(layers "B.Cu" "B.Mask" "B.Paste")
			(net "PVDDCR_CPU1_P0")
		)
		(pad "2" smd circle
			(at -0.40005 0 180)
			(size 0 0)
			(layers "B.Cu" "B.Mask" "B.Paste")
			(net "GND")
		)
	)
	(footprint ""
		(layer "B.Cu")
		(at 382.491234 -399.291302 90)
		(property "Reference" "C1016"
			(at 0 0 90)
			(layer "B.SilkS")
			(hide yes)
			(effects
				(font
					(size 1.27 1.27)
				)
				(justify mirror)
			)
		)
		(property "Value" ""
			(at 0 0 90)
			(layer "B.Fab")
			(effects
				(font
					(size 1.27 1.27)
				)
				(justify mirror)
			)
		)
		(duplicate_pad_numbers_are_jumpers no)
		(fp_line
			(start 0.299974 -0.150114)
			(end -0.299974 -0.150114)
			(stroke
				(width 0.1)
				(type default)
			)
			(layer "B.Fab")
		)
		(fp_line
			(start -0.299974 -0.150114)
			(end -0.299974 0.150114)
			(stroke
				(width 0.1)
				(type default)
			)
			(layer "B.Fab")
		)
		(fp_line
			(start 0.299974 0.150114)
			(end 0.299974 -0.150114)
			(stroke
				(width 0.1)
				(type default)
			)
			(layer "B.Fab")
		)
		(fp_line
			(start -0.299974 0.150114)
			(end 0.299974 0.150114)
			(stroke
				(width 0.1)
				(type default)
			)
			(layer "B.Fab")
		)
		(pad "1" smd rect
			(at 0.2667 0 270)
			(size 0.3048 0.381)
			(layers "B.Cu" "B.Mask" "B.Paste")
			(net "P0V9_CPU0_RT_2D")
		)
		(pad "2" smd rect
			(at -0.2667 0 270)
			(size 0.3048 0.381)
			(layers "B.Cu" "B.Mask" "B.Paste")
			(net "GND")
		)
	)
)
